FILE_TYPE = MACRO_DRAWING;
SET COLOR_WIRE YELLOW;
SET COLOR_PROP ORANGE;
SET COLOR_DOT WHITE;
SET COLOR_ARC YELLOW;
SET COLOR_BODY GREEN;
SET COLOR_NOTE PURPLE;
SET PROP_DISPLAY VALUE;
SET PAGE_NUMBER P44;
FORCEADD OFFPAGE..1
(-8450 6175);
FORCEPROP 2 LAST $XR1 13 
J 0
(-8822 6175);
DISPLAY 0.638298 (-8822 6175);
PAINT MONO (-8822 6175);
FORCEPROP 2 LAST $XR0 132 
J 0
(-8732 6175);
DISPLAY 0.638298 (-8732 6175);
PAINT MONO (-8732 6175);
FORCEPROP 2 LAST CDS_LIB standard
J 0
(-8450 6175);
PAINT MONO (-8450 6175);
DISPLAY INVISIBLE (-8450 6175);
FORCEPROP 1 LAST OFFPAGE TRUE
J 0
(-8125 6050);
DISPLAY 0.872340 (-8125 6050);
DISPLAY INVISIBLE (-8125 6050);
FORCEPROP 1 LAST COMMENT_BODY TRUE
J 0
(-8325 6075);
DISPLAY 0.872340 (-8325 6075);
PAINT GREEN (-8325 6075);
DISPLAY INVISIBLE (-8325 6075);
FORCEPROP 2 LAST PATH I1
J 0
(-8400 6250);
DISPLAY 1.021277 (-8400 6250);
DISPLAY INVISIBLE (-8400 6250);
FORCEADD Q_RES..1
(-7325 6375);
FORCEPROP 1 LAST PART_NUMBER CS03322FB03
J 0
(-7200 6350);
DISPLAY 0.404255 (-7200 6350);
DISPLAY INVISIBLE (-7200 6350);
FORCEPROP 1 LAST WATTAGE 1/16W
J 2
(-6875 6350);
DISPLAY 0.404255 (-6875 6350);
FORCEPROP 1 LAST MATERIAL CHIP
J 0
(-6850 6350);
DISPLAY 0.404255 (-6850 6350);
FORCEPROP 1 LAST TOLERANCE 1%
J 0
(-7100 6375);
DISPLAY 0.510638 (-7100 6375);
FORCEPROP 1 LAST PACK_TYPE 0402LF
J 0
(-7000 6375);
DISPLAY 0.510638 (-7000 6375);
FORCEPROP 1 LAST VALUE 33.2
J 2
(-7125 6375);
DISPLAY 0.510638 (-7125 6375);
FORCEPROP 1 LAST $LOCATION R63
J 0
(-7525 6375);
DISPLAY 0.638298 (-7525 6375);
FORCEPROP 1 LASTPIN (-7425 6375) $PN 1
J 0
(-7413 6387);
DISPLAY 0.787234 (-7413 6387);
FORCEPROP 1 LASTPIN (-7225 6375) $PN 2
J 0
(-7263 6387);
DISPLAY 0.787234 (-7263 6387);
FORCEPROP 2 LAST CDS_LIB pure_quanta
J 0
(-7325 6375);
PAINT MONO (-7325 6375);
DISPLAY INVISIBLE (-7325 6375);
FORCEPROP 1 LAST $LOCATION R63
J 0
(-7375 6575);
DISPLAY 1.021277 (-7375 6575);
DISPLAY INVISIBLE (-7375 6575);
FORCEPROP 2 LAST CDS_LOCATION R63
J 0
(-7375 6575);
DISPLAY 1.021277 (-7375 6575);
DISPLAY INVISIBLE (-7375 6575);
FORCEPROP 2 LAST $SEC 1
J 0
(-7375 6575);
DISPLAY 0.680851 (-7375 6575);
PAINT MONO (-7375 6575);
DISPLAY INVISIBLE (-7375 6575);
FORCEPROP 2 LAST CDS_SEC 1
J 0
(-7375 6575);
DISPLAY 1.021277 (-7375 6575);
DISPLAY INVISIBLE (-7375 6575);
FORCEPROP 1 LAST PATH I10
J 0
(-7375 6525);
DISPLAY 0.978723 (-7375 6525);
PAINT WHITE (-7375 6525);
DISPLAY INVISIBLE (-7375 6525);
FORCEADD Q_RES..1
(-7325 6475);
FORCEPROP 1 LAST PART_NUMBER CS11002FB07
J 0
(-7200 6450);
DISPLAY 0.404255 (-7200 6450);
DISPLAY INVISIBLE (-7200 6450);
FORCEPROP 1 LAST VALUE 100
J 2
(-7125 6475);
DISPLAY 0.510638 (-7125 6475);
FORCEPROP 1 LAST TOLERANCE 1%
J 0
(-7100 6475);
DISPLAY 0.510638 (-7100 6475);
FORCEPROP 1 LAST PACK_TYPE 0402LF
J 0
(-7000 6475);
DISPLAY 0.510638 (-7000 6475);
FORCEPROP 1 LAST MATERIAL CHIP
J 0
(-7200 6425);
DISPLAY 0.404255 (-7200 6425);
FORCEPROP 1 LAST WATTAGE 1/16W
J 2
(-6900 6425);
DISPLAY 0.404255 (-6900 6425);
FORCEPROP 1 LAST $LOCATION R62
J 0
(-7525 6475);
DISPLAY 0.638298 (-7525 6475);
FORCEPROP 1 LASTPIN (-7425 6475) $PN 1
J 0
(-7413 6487);
DISPLAY 0.787234 (-7413 6487);
FORCEPROP 1 LASTPIN (-7225 6475) $PN 2
J 0
(-7263 6487);
DISPLAY 0.787234 (-7263 6487);
FORCEPROP 2 LAST CDS_LIB pure_quanta
J 0
(-7325 6475);
PAINT MONO (-7325 6475);
DISPLAY INVISIBLE (-7325 6475);
FORCEPROP 1 LAST $LOCATION R62
J 0
(-7375 6675);
DISPLAY 1.021277 (-7375 6675);
DISPLAY INVISIBLE (-7375 6675);
FORCEPROP 2 LAST CDS_LOCATION R62
J 0
(-7375 6675);
DISPLAY 1.021277 (-7375 6675);
DISPLAY INVISIBLE (-7375 6675);
FORCEPROP 2 LAST $SEC 1
J 0
(-7375 6675);
DISPLAY 0.680851 (-7375 6675);
PAINT MONO (-7375 6675);
DISPLAY INVISIBLE (-7375 6675);
FORCEPROP 2 LAST CDS_SEC 1
J 0
(-7375 6675);
DISPLAY 1.021277 (-7375 6675);
DISPLAY INVISIBLE (-7375 6675);
FORCEPROP 1 LAST PATH I11
J 0
(-7375 6625);
DISPLAY 0.978723 (-7375 6625);
PAINT WHITE (-7375 6625);
DISPLAY INVISIBLE (-7375 6625);
FORCEADD OFFPAGE..3
R 2
(-7450 6625);
FORCEPROP 2 LAST $XR0 230 
J 0
(-7760 6625);
DISPLAY 0.638298 (-7760 6625);
PAINT MONO (-7760 6625);
FORCEPROP 2 LAST CDS_LIB standard
J 0
(-7450 6625);
DISPLAY INVISIBLE (-7450 6625);
FORCEPROP 1 LAST OFFPAGE TRUE
J 2
(-7775 6500);
DISPLAY 0.872340 (-7775 6500);
DISPLAY INVISIBLE (-7775 6500);
FORCEPROP 1 LAST COMMENT_BODY TRUE
J 2
(-7400 6525);
DISPLAY 0.872340 (-7400 6525);
PAINT GREEN (-7400 6525);
DISPLAY INVISIBLE (-7400 6525);
FORCEPROP 2 LAST PATH I12
J 0
(-7400 6700);
DISPLAY 1.021277 (-7400 6700);
DISPLAY INVISIBLE (-7400 6700);
FORCEADD OFFPAGE..2
R 2
(-7450 6675);
FORCEPROP 2 LAST $XR0 230 
J 0
(-7705 6675);
DISPLAY 0.638298 (-7705 6675);
PAINT MONO (-7705 6675);
FORCEPROP 2 LAST CDS_LIB standard
J 0
(-7450 6675);
DISPLAY INVISIBLE (-7450 6675);
FORCEPROP 1 LAST OFFPAGE TRUE
J 2
(-7775 6550);
DISPLAY 0.872340 (-7775 6550);
DISPLAY INVISIBLE (-7775 6550);
FORCEPROP 1 LAST COMMENT_BODY TRUE
J 2
(-7405 6580);
DISPLAY 0.872340 (-7405 6580);
PAINT GREEN (-7405 6580);
DISPLAY INVISIBLE (-7405 6580);
FORCEPROP 2 LAST PATH I13
J 0
(-7400 6750);
DISPLAY 1.021277 (-7400 6750);
DISPLAY INVISIBLE (-7400 6750);
FORCEADD OFFPAGE..3
R 2
(-7450 6775);
FORCEPROP 2 LAST $XR0 230 
J 0
(-7760 6775);
DISPLAY 0.638298 (-7760 6775);
PAINT MONO (-7760 6775);
FORCEPROP 2 LAST CDS_LIB standard
J 0
(-7450 6775);
DISPLAY INVISIBLE (-7450 6775);
FORCEPROP 1 LAST OFFPAGE TRUE
J 2
(-7775 6650);
DISPLAY 0.872340 (-7775 6650);
DISPLAY INVISIBLE (-7775 6650);
FORCEPROP 1 LAST COMMENT_BODY TRUE
J 2
(-7400 6675);
DISPLAY 0.872340 (-7400 6675);
PAINT GREEN (-7400 6675);
DISPLAY INVISIBLE (-7400 6675);
FORCEPROP 2 LAST PATH I14
J 0
(-7400 6850);
DISPLAY 1.021277 (-7400 6850);
DISPLAY INVISIBLE (-7400 6850);
FORCEADD OFFPAGE..2
R 2
(-7450 6825);
FORCEPROP 2 LAST $XR0 230 
J 0
(-7705 6825);
DISPLAY 0.638298 (-7705 6825);
PAINT MONO (-7705 6825);
FORCEPROP 2 LAST CDS_LIB standard
J 0
(-7450 6825);
DISPLAY INVISIBLE (-7450 6825);
FORCEPROP 1 LAST OFFPAGE TRUE
J 2
(-7775 6700);
DISPLAY 0.872340 (-7775 6700);
DISPLAY INVISIBLE (-7775 6700);
FORCEPROP 1 LAST COMMENT_BODY TRUE
J 2
(-7405 6730);
DISPLAY 0.872340 (-7405 6730);
PAINT GREEN (-7405 6730);
DISPLAY INVISIBLE (-7405 6730);
FORCEPROP 2 LAST PATH I15
J 0
(-7400 6900);
DISPLAY 1.021277 (-7400 6900);
DISPLAY INVISIBLE (-7400 6900);
FORCEADD Q_RES..1
(-7325 6525);
FORCEPROP 1 LAST PART_NUMBER CS01002FB07
J 0
(-7200 6550);
DISPLAY 0.404255 (-7200 6550);
DISPLAY INVISIBLE (-7200 6550);
FORCEPROP 1 LAST VALUE 10
J 2
(-7150 6525);
DISPLAY 0.510638 (-7150 6525);
FORCEPROP 1 LAST TOLERANCE 1%
J 0
(-7100 6525);
DISPLAY 0.510638 (-7100 6525);
FORCEPROP 1 LAST MATERIAL CHIP
J 0
(-7200 6575);
DISPLAY 0.404255 (-7200 6575);
FORCEPROP 1 LAST WATTAGE 1/16W
J 2
(-6900 6575);
DISPLAY 0.404255 (-6900 6575);
FORCEPROP 1 LAST PACK_TYPE 0402LF
J 0
(-7000 6525);
DISPLAY 0.510638 (-7000 6525);
FORCEPROP 1 LAST $LOCATION R61
J 0
(-7525 6525);
DISPLAY 0.638298 (-7525 6525);
FORCEPROP 1 LASTPIN (-7425 6525) $PN 1
J 0
(-7413 6537);
DISPLAY 0.787234 (-7413 6537);
FORCEPROP 1 LASTPIN (-7225 6525) $PN 2
J 0
(-7263 6537);
DISPLAY 0.787234 (-7263 6537);
FORCEPROP 2 LAST CDS_LIB pure_quanta
J 0
(-7325 6525);
PAINT MONO (-7325 6525);
DISPLAY INVISIBLE (-7325 6525);
FORCEPROP 1 LAST $LOCATION R61
J 0
(-7375 6725);
DISPLAY 1.021277 (-7375 6725);
DISPLAY INVISIBLE (-7375 6725);
FORCEPROP 2 LAST CDS_LOCATION R61
J 0
(-7375 6725);
DISPLAY 1.021277 (-7375 6725);
DISPLAY INVISIBLE (-7375 6725);
FORCEPROP 2 LAST $SEC 1
J 0
(-7375 6725);
DISPLAY 0.680851 (-7375 6725);
PAINT MONO (-7375 6725);
DISPLAY INVISIBLE (-7375 6725);
FORCEPROP 2 LAST CDS_SEC 1
J 0
(-7375 6725);
DISPLAY 1.021277 (-7375 6725);
DISPLAY INVISIBLE (-7375 6725);
FORCEPROP 1 LAST PATH I16
J 0
(-7375 6675);
DISPLAY 0.978723 (-7375 6675);
PAINT WHITE (-7375 6675);
DISPLAY INVISIBLE (-7375 6675);
FORCEADD OFFPAGE..1
(-7450 7425);
FORCEPROP 2 LAST $XR0 209 
J 0
(-7732 7425);
DISPLAY 0.638298 (-7732 7425);
PAINT MONO (-7732 7425);
FORCEPROP 2 LAST CDS_LIB standard
J 0
(-7450 7425);
DISPLAY INVISIBLE (-7450 7425);
FORCEPROP 1 LAST OFFPAGE TRUE
J 0
(-7125 7300);
DISPLAY 0.872340 (-7125 7300);
DISPLAY INVISIBLE (-7125 7300);
FORCEPROP 1 LAST COMMENT_BODY TRUE
J 0
(-7325 7325);
DISPLAY 0.872340 (-7325 7325);
PAINT GREEN (-7325 7325);
DISPLAY INVISIBLE (-7325 7325);
FORCEPROP 2 LAST PATH I17
J 0
(-7400 7500);
DISPLAY 1.021277 (-7400 7500);
DISPLAY INVISIBLE (-7400 7500);
FORCEADD OFFPAGE..1
(-7450 7375);
FORCEPROP 2 LAST $XR0 209 
J 0
(-7732 7375);
DISPLAY 0.638298 (-7732 7375);
PAINT MONO (-7732 7375);
FORCEPROP 2 LAST CDS_LIB standard
J 0
(-7450 7375);
DISPLAY INVISIBLE (-7450 7375);
FORCEPROP 1 LAST OFFPAGE TRUE
J 0
(-7125 7250);
DISPLAY 0.872340 (-7125 7250);
DISPLAY INVISIBLE (-7125 7250);
FORCEPROP 1 LAST COMMENT_BODY TRUE
J 0
(-7325 7275);
DISPLAY 0.872340 (-7325 7275);
PAINT GREEN (-7325 7275);
DISPLAY INVISIBLE (-7325 7275);
FORCEPROP 2 LAST PATH I18
J 0
(-7400 7450);
DISPLAY 1.021277 (-7400 7450);
DISPLAY INVISIBLE (-7400 7450);
FORCEADD OFFPAGE..1
(-7450 7525);
FORCEPROP 2 LAST $XR0 206 
J 0
(-7732 7525);
DISPLAY 0.638298 (-7732 7525);
PAINT MONO (-7732 7525);
FORCEPROP 2 LAST CDS_LIB standard
J 0
(-7450 7525);
DISPLAY INVISIBLE (-7450 7525);
FORCEPROP 1 LAST OFFPAGE TRUE
J 0
(-7125 7400);
DISPLAY 0.872340 (-7125 7400);
DISPLAY INVISIBLE (-7125 7400);
FORCEPROP 1 LAST COMMENT_BODY TRUE
J 0
(-7325 7425);
DISPLAY 0.872340 (-7325 7425);
PAINT GREEN (-7325 7425);
DISPLAY INVISIBLE (-7325 7425);
FORCEPROP 2 LAST PATH I19
J 0
(-7400 7600);
DISPLAY 1.021277 (-7400 7600);
DISPLAY INVISIBLE (-7400 7600);
FORCEADD OFFPAGE..1
(-8450 6225);
FORCEPROP 2 LAST $XR3 13 
J 0
(-9062 6225);
DISPLAY 0.638298 (-9062 6225);
PAINT MONO (-9062 6225);
FORCEPROP 2 LAST $XR2 182 
J 0
(-8972 6225);
DISPLAY 0.638298 (-8972 6225);
PAINT MONO (-8972 6225);
FORCEPROP 2 LAST $XR1 134 
J 0
(-8852 6225);
DISPLAY 0.638298 (-8852 6225);
PAINT MONO (-8852 6225);
FORCEPROP 2 LAST $XR0 131 
J 0
(-8732 6225);
DISPLAY 0.638298 (-8732 6225);
PAINT MONO (-8732 6225);
FORCEPROP 2 LAST CDS_LIB standard
J 0
(-8450 6225);
PAINT MONO (-8450 6225);
DISPLAY INVISIBLE (-8450 6225);
FORCEPROP 1 LAST OFFPAGE TRUE
J 0
(-8125 6100);
DISPLAY 0.872340 (-8125 6100);
DISPLAY INVISIBLE (-8125 6100);
FORCEPROP 1 LAST COMMENT_BODY TRUE
J 0
(-8325 6125);
DISPLAY 0.872340 (-8325 6125);
PAINT GREEN (-8325 6125);
DISPLAY INVISIBLE (-8325 6125);
FORCEPROP 2 LAST PATH I2
J 0
(-8400 6300);
DISPLAY 1.021277 (-8400 6300);
DISPLAY INVISIBLE (-8400 6300);
FORCEADD OFFPAGE..1
(-7450 7675);
FORCEPROP 2 LAST $XR0 206 
J 0
(-7732 7675);
DISPLAY 0.638298 (-7732 7675);
PAINT MONO (-7732 7675);
FORCEPROP 2 LAST CDS_LIB standard
J 0
(-7450 7675);
DISPLAY INVISIBLE (-7450 7675);
FORCEPROP 1 LAST OFFPAGE TRUE
J 0
(-7125 7550);
DISPLAY 0.872340 (-7125 7550);
DISPLAY INVISIBLE (-7125 7550);
FORCEPROP 1 LAST COMMENT_BODY TRUE
J 0
(-7325 7575);
DISPLAY 0.872340 (-7325 7575);
PAINT GREEN (-7325 7575);
DISPLAY INVISIBLE (-7325 7575);
FORCEPROP 2 LAST PATH I20
J 0
(-7400 7750);
DISPLAY 1.021277 (-7400 7750);
DISPLAY INVISIBLE (-7400 7750);
FORCEADD OFFPAGE..1
(-7450 7575);
FORCEPROP 2 LAST $XR0 206 
J 0
(-7732 7575);
DISPLAY 0.638298 (-7732 7575);
PAINT MONO (-7732 7575);
FORCEPROP 2 LAST CDS_LIB standard
J 0
(-7450 7575);
DISPLAY INVISIBLE (-7450 7575);
FORCEPROP 1 LAST OFFPAGE TRUE
J 0
(-7125 7450);
DISPLAY 0.872340 (-7125 7450);
DISPLAY INVISIBLE (-7125 7450);
FORCEPROP 1 LAST COMMENT_BODY TRUE
J 0
(-7325 7475);
DISPLAY 0.872340 (-7325 7475);
PAINT GREEN (-7325 7475);
DISPLAY INVISIBLE (-7325 7475);
FORCEPROP 2 LAST PATH I21
J 0
(-7400 7650);
DISPLAY 1.021277 (-7400 7650);
DISPLAY INVISIBLE (-7400 7650);
FORCEADD OFFPAGE..1
(-7450 7725);
FORCEPROP 2 LAST $XR0 206 
J 0
(-7732 7725);
DISPLAY 0.638298 (-7732 7725);
PAINT MONO (-7732 7725);
FORCEPROP 2 LAST CDS_LIB standard
J 0
(-7450 7725);
DISPLAY INVISIBLE (-7450 7725);
FORCEPROP 1 LAST OFFPAGE TRUE
J 0
(-7125 7600);
DISPLAY 0.872340 (-7125 7600);
DISPLAY INVISIBLE (-7125 7600);
FORCEPROP 1 LAST COMMENT_BODY TRUE
J 0
(-7325 7625);
DISPLAY 0.872340 (-7325 7625);
PAINT GREEN (-7325 7625);
DISPLAY INVISIBLE (-7325 7625);
FORCEPROP 2 LAST PATH I22
J 0
(-7400 7800);
DISPLAY 1.021277 (-7400 7800);
DISPLAY INVISIBLE (-7400 7800);
FORCEADD OFFPAGE..1
(-7450 7825);
FORCEPROP 2 LAST $XR0 206 
J 0
(-7732 7825);
DISPLAY 0.638298 (-7732 7825);
PAINT MONO (-7732 7825);
FORCEPROP 2 LAST CDS_LIB standard
J 0
(-7450 7825);
DISPLAY INVISIBLE (-7450 7825);
FORCEPROP 1 LAST OFFPAGE TRUE
J 0
(-7125 7700);
DISPLAY 0.872340 (-7125 7700);
DISPLAY INVISIBLE (-7125 7700);
FORCEPROP 1 LAST COMMENT_BODY TRUE
J 0
(-7325 7725);
DISPLAY 0.872340 (-7325 7725);
PAINT GREEN (-7325 7725);
DISPLAY INVISIBLE (-7325 7725);
FORCEPROP 2 LAST PATH I23
J 0
(-7400 7900);
DISPLAY 1.021277 (-7400 7900);
DISPLAY INVISIBLE (-7400 7900);
FORCEADD OFFPAGE..1
(-7450 7975);
FORCEPROP 2 LAST $XR0 206 
J 0
(-7732 7975);
DISPLAY 0.638298 (-7732 7975);
PAINT MONO (-7732 7975);
FORCEPROP 2 LAST CDS_LIB standard
J 0
(-7450 7975);
DISPLAY INVISIBLE (-7450 7975);
FORCEPROP 1 LAST OFFPAGE TRUE
J 0
(-7125 7850);
DISPLAY 0.872340 (-7125 7850);
DISPLAY INVISIBLE (-7125 7850);
FORCEPROP 1 LAST COMMENT_BODY TRUE
J 0
(-7325 7875);
DISPLAY 0.872340 (-7325 7875);
PAINT GREEN (-7325 7875);
DISPLAY INVISIBLE (-7325 7875);
FORCEPROP 2 LAST PATH I24
J 0
(-7400 8050);
DISPLAY 1.021277 (-7400 8050);
DISPLAY INVISIBLE (-7400 8050);
FORCEADD OFFPAGE..1
(-7450 7875);
FORCEPROP 2 LAST $XR0 206 
J 0
(-7732 7875);
DISPLAY 0.638298 (-7732 7875);
PAINT MONO (-7732 7875);
FORCEPROP 2 LAST CDS_LIB standard
J 0
(-7450 7875);
DISPLAY INVISIBLE (-7450 7875);
FORCEPROP 1 LAST OFFPAGE TRUE
J 0
(-7125 7750);
DISPLAY 0.872340 (-7125 7750);
DISPLAY INVISIBLE (-7125 7750);
FORCEPROP 1 LAST COMMENT_BODY TRUE
J 0
(-7325 7775);
DISPLAY 0.872340 (-7325 7775);
PAINT GREEN (-7325 7775);
DISPLAY INVISIBLE (-7325 7775);
FORCEPROP 2 LAST PATH I25
J 0
(-7400 7950);
DISPLAY 1.021277 (-7400 7950);
DISPLAY INVISIBLE (-7400 7950);
FORCEADD OFFPAGE..1
(-7450 8025);
FORCEPROP 2 LAST $XR0 206 
J 0
(-7732 8025);
DISPLAY 0.638298 (-7732 8025);
PAINT MONO (-7732 8025);
FORCEPROP 2 LAST CDS_LIB standard
J 0
(-7450 8025);
DISPLAY INVISIBLE (-7450 8025);
FORCEPROP 1 LAST OFFPAGE TRUE
J 0
(-7125 7900);
DISPLAY 0.872340 (-7125 7900);
DISPLAY INVISIBLE (-7125 7900);
FORCEPROP 1 LAST COMMENT_BODY TRUE
J 0
(-7325 7925);
DISPLAY 0.872340 (-7325 7925);
PAINT GREEN (-7325 7925);
DISPLAY INVISIBLE (-7325 7925);
FORCEPROP 2 LAST PATH I26
J 0
(-7400 8100);
DISPLAY 1.021277 (-7400 8100);
DISPLAY INVISIBLE (-7400 8100);
FORCEADD OFFPAGE..2
(-1550 6175);
FORCEPROP 2 LAST $XR0 133 
J 0
(-1361 6175);
DISPLAY 0.638298 (-1361 6175);
PAINT MONO (-1361 6175);
FORCEPROP 2 LAST CDS_LIB standard
J 0
(-1550 6175);
PAINT MONO (-1550 6175);
DISPLAY INVISIBLE (-1550 6175);
FORCEPROP 1 LAST OFFPAGE TRUE
J 0
(-1225 6050);
DISPLAY 1.170213 (-1225 6050);
PAINT GREEN (-1225 6050);
DISPLAY INVISIBLE (-1225 6050);
FORCEPROP 1 LAST COMMENT_BODY TRUE
J 0
(-1595 6080);
DISPLAY 1.170213 (-1595 6080);
PAINT GREEN (-1595 6080);
DISPLAY INVISIBLE (-1595 6080);
FORCEPROP 2 LAST PATH I28
J 0
(-1375 6250);
DISPLAY 1.021277 (-1375 6250);
DISPLAY INVISIBLE (-1375 6250);
FORCEADD OFFPAGE..3
R 2
(-8450 6375);
FORCEPROP 2 LAST $XR1 197 
J 0
(-8849 6375);
DISPLAY 0.638298 (-8849 6375);
PAINT MONO (-8849 6375);
FORCEPROP 2 LAST $XR0 13 
J 0
(-8729 6375);
DISPLAY 0.638298 (-8729 6375);
PAINT MONO (-8729 6375);
FORCEPROP 2 LAST CDS_LIB standard
J 0
(-8450 6375);
PAINT MONO (-8450 6375);
DISPLAY INVISIBLE (-8450 6375);
FORCEPROP 1 LAST OFFPAGE TRUE
J 2
(-8775 6250);
DISPLAY 0.872340 (-8775 6250);
DISPLAY INVISIBLE (-8775 6250);
FORCEPROP 1 LAST COMMENT_BODY TRUE
J 2
(-8400 6275);
DISPLAY 0.872340 (-8400 6275);
PAINT GREEN (-8400 6275);
DISPLAY INVISIBLE (-8400 6275);
FORCEPROP 2 LAST PATH I3
J 0
(-8400 6450);
DISPLAY 1.021277 (-8400 6450);
DISPLAY INVISIBLE (-8400 6450);
FORCEADD OFFPAGE..2
(-1550 6725);
FORCEPROP 2 LAST $XR0 128 
J 0
(-1361 6725);
DISPLAY 0.638298 (-1361 6725);
PAINT MONO (-1361 6725);
FORCEPROP 2 LAST CDS_LIB standard
J 0
(-1550 6725);
PAINT MONO (-1550 6725);
DISPLAY INVISIBLE (-1550 6725);
FORCEPROP 1 LAST OFFPAGE TRUE
J 0
(-1225 6600);
DISPLAY 1.170213 (-1225 6600);
PAINT GREEN (-1225 6600);
DISPLAY INVISIBLE (-1225 6600);
FORCEPROP 1 LAST COMMENT_BODY TRUE
J 0
(-1595 6630);
DISPLAY 1.170213 (-1595 6630);
PAINT GREEN (-1595 6630);
DISPLAY INVISIBLE (-1595 6630);
FORCEPROP 2 LAST PATH I30
J 0
(-1375 6800);
DISPLAY 1.021277 (-1375 6800);
DISPLAY INVISIBLE (-1375 6800);
FORCEADD OFFPAGE..2
(-1550 6775);
FORCEPROP 2 LAST $XR0 128 
J 0
(-1361 6775);
DISPLAY 0.638298 (-1361 6775);
PAINT MONO (-1361 6775);
FORCEPROP 2 LAST CDS_LIB standard
J 0
(-1550 6775);
PAINT MONO (-1550 6775);
DISPLAY INVISIBLE (-1550 6775);
FORCEPROP 1 LAST OFFPAGE TRUE
J 0
(-1225 6650);
DISPLAY 1.170213 (-1225 6650);
PAINT GREEN (-1225 6650);
DISPLAY INVISIBLE (-1225 6650);
FORCEPROP 1 LAST COMMENT_BODY TRUE
J 0
(-1595 6680);
DISPLAY 1.170213 (-1595 6680);
PAINT GREEN (-1595 6680);
DISPLAY INVISIBLE (-1595 6680);
FORCEPROP 2 LAST PATH I31
J 0
(-1375 6850);
DISPLAY 1.021277 (-1375 6850);
DISPLAY INVISIBLE (-1375 6850);
FORCEADD OFFPAGE..2
(-1550 6825);
FORCEPROP 2 LAST $XR0 128 
J 0
(-1361 6825);
DISPLAY 0.638298 (-1361 6825);
PAINT MONO (-1361 6825);
FORCEPROP 2 LAST CDS_LIB standard
J 0
(-1550 6825);
PAINT MONO (-1550 6825);
DISPLAY INVISIBLE (-1550 6825);
FORCEPROP 1 LAST OFFPAGE TRUE
J 0
(-1225 6700);
DISPLAY 1.170213 (-1225 6700);
PAINT GREEN (-1225 6700);
DISPLAY INVISIBLE (-1225 6700);
FORCEPROP 1 LAST COMMENT_BODY TRUE
J 0
(-1595 6730);
DISPLAY 1.170213 (-1595 6730);
PAINT GREEN (-1595 6730);
DISPLAY INVISIBLE (-1595 6730);
FORCEPROP 2 LAST PATH I32
J 0
(-1375 6900);
DISPLAY 1.021277 (-1375 6900);
DISPLAY INVISIBLE (-1375 6900);
FORCEADD OFFPAGE..2
(-1550 6875);
FORCEPROP 2 LAST $XR0 128 
J 0
(-1361 6875);
DISPLAY 0.638298 (-1361 6875);
PAINT MONO (-1361 6875);
FORCEPROP 2 LAST CDS_LIB standard
J 0
(-1550 6875);
PAINT MONO (-1550 6875);
DISPLAY INVISIBLE (-1550 6875);
FORCEPROP 1 LAST OFFPAGE TRUE
J 0
(-1225 6750);
DISPLAY 1.170213 (-1225 6750);
PAINT GREEN (-1225 6750);
DISPLAY INVISIBLE (-1225 6750);
FORCEPROP 1 LAST COMMENT_BODY TRUE
J 0
(-1595 6780);
DISPLAY 1.170213 (-1595 6780);
PAINT GREEN (-1595 6780);
DISPLAY INVISIBLE (-1595 6780);
FORCEPROP 2 LAST PATH I33
J 0
(-1375 6950);
DISPLAY 1.021277 (-1375 6950);
DISPLAY INVISIBLE (-1375 6950);
FORCEADD OFFPAGE..4
(-1550 6975);
FORCEPROP 2 LAST $XR0 119 
J 0
(-1364 6975);
DISPLAY 0.638298 (-1364 6975);
PAINT MONO (-1364 6975);
FORCEPROP 2 LAST CDS_LIB standard
J 0
(-1550 6975);
PAINT MONO (-1550 6975);
DISPLAY INVISIBLE (-1550 6975);
FORCEPROP 1 LAST OFFPAGE TRUE
J 0
(-1225 6850);
DISPLAY 1.170213 (-1225 6850);
PAINT GREEN (-1225 6850);
DISPLAY INVISIBLE (-1225 6850);
FORCEPROP 1 LAST COMMENT_BODY TRUE
J 0
(-1575 6875);
DISPLAY 1.170213 (-1575 6875);
PAINT GREEN (-1575 6875);
DISPLAY INVISIBLE (-1575 6875);
FORCEPROP 2 LAST PATH I34
J 0
(-1375 7050);
DISPLAY 1.021277 (-1375 7050);
DISPLAY INVISIBLE (-1375 7050);
FORCEADD OFFPAGE..4
(-1550 7025);
FORCEPROP 2 LAST $XR0 119 
J 0
(-1364 7025);
DISPLAY 0.638298 (-1364 7025);
PAINT MONO (-1364 7025);
FORCEPROP 2 LAST CDS_LIB standard
J 0
(-1550 7025);
PAINT MONO (-1550 7025);
DISPLAY INVISIBLE (-1550 7025);
FORCEPROP 1 LAST OFFPAGE TRUE
J 0
(-1225 6900);
DISPLAY 1.170213 (-1225 6900);
PAINT GREEN (-1225 6900);
DISPLAY INVISIBLE (-1225 6900);
FORCEPROP 1 LAST COMMENT_BODY TRUE
J 0
(-1575 6925);
DISPLAY 1.170213 (-1575 6925);
PAINT GREEN (-1575 6925);
DISPLAY INVISIBLE (-1575 6925);
FORCEPROP 2 LAST PATH I35
J 0
(-1375 7100);
DISPLAY 1.021277 (-1375 7100);
DISPLAY INVISIBLE (-1375 7100);
FORCEADD OFFPAGE..4
(-1550 7125);
FORCEPROP 2 LAST $XR0 119 
J 0
(-1364 7125);
DISPLAY 0.638298 (-1364 7125);
PAINT MONO (-1364 7125);
FORCEPROP 2 LAST CDS_LIB standard
J 0
(-1550 7125);
PAINT MONO (-1550 7125);
DISPLAY INVISIBLE (-1550 7125);
FORCEPROP 1 LAST OFFPAGE TRUE
J 0
(-1225 7000);
DISPLAY 1.170213 (-1225 7000);
PAINT GREEN (-1225 7000);
DISPLAY INVISIBLE (-1225 7000);
FORCEPROP 1 LAST COMMENT_BODY TRUE
J 0
(-1575 7025);
DISPLAY 1.170213 (-1575 7025);
PAINT GREEN (-1575 7025);
DISPLAY INVISIBLE (-1575 7025);
FORCEPROP 2 LAST PATH I36
J 0
(-1375 7200);
DISPLAY 1.021277 (-1375 7200);
DISPLAY INVISIBLE (-1375 7200);
FORCEADD OFFPAGE..2
(-1550 7275);
FORCEPROP 2 LAST $XR1 214 
J 0
(-1241 7275);
DISPLAY 0.638298 (-1241 7275);
PAINT MONO (-1241 7275);
FORCEPROP 2 LAST $XR0 119 
J 0
(-1361 7275);
DISPLAY 0.638298 (-1361 7275);
PAINT MONO (-1361 7275);
FORCEPROP 2 LAST CDS_LIB standard
J 0
(-1550 7275);
PAINT MONO (-1550 7275);
DISPLAY INVISIBLE (-1550 7275);
FORCEPROP 1 LAST OFFPAGE TRUE
J 0
(-1225 7150);
DISPLAY 1.170213 (-1225 7150);
PAINT GREEN (-1225 7150);
DISPLAY INVISIBLE (-1225 7150);
FORCEPROP 1 LAST COMMENT_BODY TRUE
J 0
(-1595 7180);
DISPLAY 1.170213 (-1595 7180);
PAINT GREEN (-1595 7180);
DISPLAY INVISIBLE (-1595 7180);
FORCEPROP 2 LAST PATH I38
J 0
(-1375 7350);
DISPLAY 1.021277 (-1375 7350);
DISPLAY INVISIBLE (-1375 7350);
FORCEADD OFFPAGE..2
(-1550 7325);
FORCEPROP 2 LAST $XR1 214 
J 0
(-1241 7325);
DISPLAY 0.638298 (-1241 7325);
PAINT MONO (-1241 7325);
FORCEPROP 2 LAST $XR0 119 
J 0
(-1361 7325);
DISPLAY 0.638298 (-1361 7325);
PAINT MONO (-1361 7325);
FORCEPROP 2 LAST CDS_LIB standard
J 0
(-1550 7325);
PAINT MONO (-1550 7325);
DISPLAY INVISIBLE (-1550 7325);
FORCEPROP 1 LAST OFFPAGE TRUE
J 0
(-1225 7200);
DISPLAY 1.170213 (-1225 7200);
PAINT GREEN (-1225 7200);
DISPLAY INVISIBLE (-1225 7200);
FORCEPROP 1 LAST COMMENT_BODY TRUE
J 0
(-1595 7230);
DISPLAY 1.170213 (-1595 7230);
PAINT GREEN (-1595 7230);
DISPLAY INVISIBLE (-1595 7230);
FORCEPROP 2 LAST PATH I39
J 0
(-1375 7400);
DISPLAY 1.021277 (-1375 7400);
DISPLAY INVISIBLE (-1375 7400);
FORCEADD OFFPAGE..1
(-8450 6275);
FORCEPROP 2 LAST $XR0 133 
J 0
(-8732 6275);
DISPLAY 0.638298 (-8732 6275);
PAINT MONO (-8732 6275);
FORCEPROP 2 LAST CDS_LIB standard
J 0
(-8450 6275);
PAINT MONO (-8450 6275);
DISPLAY INVISIBLE (-8450 6275);
FORCEPROP 1 LAST OFFPAGE TRUE
J 0
(-8125 6150);
DISPLAY 0.872340 (-8125 6150);
DISPLAY INVISIBLE (-8125 6150);
FORCEPROP 1 LAST COMMENT_BODY TRUE
J 0
(-8325 6175);
DISPLAY 0.872340 (-8325 6175);
PAINT GREEN (-8325 6175);
DISPLAY INVISIBLE (-8325 6175);
FORCEPROP 2 LAST PATH I4
J 0
(-8400 6350);
DISPLAY 1.021277 (-8400 6350);
DISPLAY INVISIBLE (-8400 6350);
FORCEADD OFFPAGE..2
(-1550 7375);
FORCEPROP 2 LAST $XR1 214 
J 0
(-1241 7375);
DISPLAY 0.638298 (-1241 7375);
PAINT MONO (-1241 7375);
FORCEPROP 2 LAST $XR0 119 
J 0
(-1361 7375);
DISPLAY 0.638298 (-1361 7375);
PAINT MONO (-1361 7375);
FORCEPROP 2 LAST CDS_LIB standard
J 0
(-1550 7375);
PAINT MONO (-1550 7375);
DISPLAY INVISIBLE (-1550 7375);
FORCEPROP 1 LAST OFFPAGE TRUE
J 0
(-1225 7250);
DISPLAY 1.170213 (-1225 7250);
PAINT GREEN (-1225 7250);
DISPLAY INVISIBLE (-1225 7250);
FORCEPROP 1 LAST COMMENT_BODY TRUE
J 0
(-1595 7280);
DISPLAY 1.170213 (-1595 7280);
PAINT GREEN (-1595 7280);
DISPLAY INVISIBLE (-1595 7280);
FORCEPROP 2 LAST PATH I40
J 0
(-1375 7450);
DISPLAY 1.021277 (-1375 7450);
DISPLAY INVISIBLE (-1375 7450);
FORCEADD OFFPAGE..2
(-1550 7425);
FORCEPROP 2 LAST $XR1 214 
J 0
(-1241 7425);
DISPLAY 0.638298 (-1241 7425);
PAINT MONO (-1241 7425);
FORCEPROP 2 LAST $XR0 119 
J 0
(-1361 7425);
DISPLAY 0.638298 (-1361 7425);
PAINT MONO (-1361 7425);
FORCEPROP 2 LAST CDS_LIB standard
J 0
(-1550 7425);
PAINT MONO (-1550 7425);
DISPLAY INVISIBLE (-1550 7425);
FORCEPROP 1 LAST OFFPAGE TRUE
J 0
(-1225 7300);
DISPLAY 1.170213 (-1225 7300);
PAINT GREEN (-1225 7300);
DISPLAY INVISIBLE (-1225 7300);
FORCEPROP 1 LAST COMMENT_BODY TRUE
J 0
(-1595 7330);
DISPLAY 1.170213 (-1595 7330);
PAINT GREEN (-1595 7330);
DISPLAY INVISIBLE (-1595 7330);
FORCEPROP 2 LAST PATH I41
J 0
(-1375 7500);
DISPLAY 1.021277 (-1375 7500);
DISPLAY INVISIBLE (-1375 7500);
FORCEADD OFFPAGE..2
(-1550 7475);
FORCEPROP 2 LAST $XR1 214 
J 0
(-1241 7475);
DISPLAY 0.638298 (-1241 7475);
PAINT MONO (-1241 7475);
FORCEPROP 2 LAST $XR0 119 
J 0
(-1361 7475);
DISPLAY 0.638298 (-1361 7475);
PAINT MONO (-1361 7475);
FORCEPROP 2 LAST CDS_LIB standard
J 0
(-1550 7475);
PAINT MONO (-1550 7475);
DISPLAY INVISIBLE (-1550 7475);
FORCEPROP 1 LAST OFFPAGE TRUE
J 0
(-1225 7350);
DISPLAY 1.170213 (-1225 7350);
PAINT GREEN (-1225 7350);
DISPLAY INVISIBLE (-1225 7350);
FORCEPROP 1 LAST COMMENT_BODY TRUE
J 0
(-1595 7380);
DISPLAY 1.170213 (-1595 7380);
PAINT GREEN (-1595 7380);
DISPLAY INVISIBLE (-1595 7380);
FORCEPROP 2 LAST PATH I42
J 0
(-1375 7550);
DISPLAY 1.021277 (-1375 7550);
DISPLAY INVISIBLE (-1375 7550);
FORCEADD OFFPAGE..4
(-1550 7525);
FORCEPROP 2 LAST $XR0 119 
J 0
(-1364 7525);
DISPLAY 0.638298 (-1364 7525);
PAINT MONO (-1364 7525);
FORCEPROP 2 LAST CDS_LIB standard
J 0
(-1550 7525);
PAINT MONO (-1550 7525);
DISPLAY INVISIBLE (-1550 7525);
FORCEPROP 1 LAST OFFPAGE TRUE
J 0
(-1225 7400);
DISPLAY 1.170213 (-1225 7400);
PAINT GREEN (-1225 7400);
DISPLAY INVISIBLE (-1225 7400);
FORCEPROP 1 LAST COMMENT_BODY TRUE
J 0
(-1575 7425);
DISPLAY 1.170213 (-1575 7425);
PAINT GREEN (-1575 7425);
DISPLAY INVISIBLE (-1575 7425);
FORCEPROP 2 LAST PATH I43
J 0
(-1375 7600);
DISPLAY 1.021277 (-1375 7600);
DISPLAY INVISIBLE (-1375 7600);
FORCEADD OFFPAGE..4
(-1550 7575);
FORCEPROP 2 LAST $XR0 119 
J 0
(-1364 7575);
DISPLAY 0.638298 (-1364 7575);
PAINT MONO (-1364 7575);
FORCEPROP 2 LAST CDS_LIB standard
J 0
(-1550 7575);
PAINT MONO (-1550 7575);
DISPLAY INVISIBLE (-1550 7575);
FORCEPROP 1 LAST OFFPAGE TRUE
J 0
(-1225 7450);
DISPLAY 1.170213 (-1225 7450);
PAINT GREEN (-1225 7450);
DISPLAY INVISIBLE (-1225 7450);
FORCEPROP 1 LAST COMMENT_BODY TRUE
J 0
(-1575 7475);
DISPLAY 1.170213 (-1575 7475);
PAINT GREEN (-1575 7475);
DISPLAY INVISIBLE (-1575 7475);
FORCEPROP 2 LAST PATH I44
J 0
(-1375 7650);
DISPLAY 1.021277 (-1375 7650);
DISPLAY INVISIBLE (-1375 7650);
FORCEADD OFFPAGE..4
(-1550 7625);
FORCEPROP 2 LAST $XR0 119 
J 0
(-1364 7625);
DISPLAY 0.638298 (-1364 7625);
PAINT MONO (-1364 7625);
FORCEPROP 2 LAST CDS_LIB standard
J 0
(-1550 7625);
PAINT MONO (-1550 7625);
DISPLAY INVISIBLE (-1550 7625);
FORCEPROP 1 LAST OFFPAGE TRUE
J 0
(-1225 7500);
DISPLAY 1.170213 (-1225 7500);
PAINT GREEN (-1225 7500);
DISPLAY INVISIBLE (-1225 7500);
FORCEPROP 1 LAST COMMENT_BODY TRUE
J 0
(-1575 7525);
DISPLAY 1.170213 (-1575 7525);
PAINT GREEN (-1575 7525);
DISPLAY INVISIBLE (-1575 7525);
FORCEPROP 2 LAST PATH I45
J 0
(-1375 7700);
DISPLAY 1.021277 (-1375 7700);
DISPLAY INVISIBLE (-1375 7700);
FORCEADD OFFPAGE..4
(-1550 7725);
FORCEPROP 2 LAST $XR0 119 
J 0
(-1364 7725);
DISPLAY 0.638298 (-1364 7725);
PAINT MONO (-1364 7725);
FORCEPROP 2 LAST CDS_LIB standard
J 0
(-1550 7725);
PAINT MONO (-1550 7725);
DISPLAY INVISIBLE (-1550 7725);
FORCEPROP 1 LAST OFFPAGE TRUE
J 0
(-1225 7600);
DISPLAY 1.170213 (-1225 7600);
PAINT GREEN (-1225 7600);
DISPLAY INVISIBLE (-1225 7600);
FORCEPROP 1 LAST COMMENT_BODY TRUE
J 0
(-1575 7625);
DISPLAY 1.170213 (-1575 7625);
PAINT GREEN (-1575 7625);
DISPLAY INVISIBLE (-1575 7625);
FORCEPROP 2 LAST PATH I46
J 0
(-1375 7800);
DISPLAY 1.021277 (-1375 7800);
DISPLAY INVISIBLE (-1375 7800);
FORCEADD OFFPAGE..4
(-1550 7825);
FORCEPROP 2 LAST $XR0 119 
J 0
(-1364 7825);
DISPLAY 0.638298 (-1364 7825);
PAINT MONO (-1364 7825);
FORCEPROP 2 LAST CDS_LIB standard
J 0
(-1550 7825);
PAINT MONO (-1550 7825);
DISPLAY INVISIBLE (-1550 7825);
FORCEPROP 1 LAST OFFPAGE TRUE
J 0
(-1225 7700);
DISPLAY 1.170213 (-1225 7700);
PAINT GREEN (-1225 7700);
DISPLAY INVISIBLE (-1225 7700);
FORCEPROP 1 LAST COMMENT_BODY TRUE
J 0
(-1575 7725);
DISPLAY 1.170213 (-1575 7725);
PAINT GREEN (-1575 7725);
DISPLAY INVISIBLE (-1575 7725);
FORCEPROP 2 LAST PATH I47
J 0
(-1375 7900);
DISPLAY 1.021277 (-1375 7900);
DISPLAY INVISIBLE (-1375 7900);
FORCEADD OFFPAGE..4
(-1550 7925);
FORCEPROP 2 LAST $XR0 119 
J 0
(-1364 7925);
DISPLAY 0.638298 (-1364 7925);
PAINT MONO (-1364 7925);
FORCEPROP 2 LAST CDS_LIB standard
J 0
(-1550 7925);
PAINT MONO (-1550 7925);
DISPLAY INVISIBLE (-1550 7925);
FORCEPROP 1 LAST OFFPAGE TRUE
J 0
(-1225 7800);
DISPLAY 1.170213 (-1225 7800);
PAINT GREEN (-1225 7800);
DISPLAY INVISIBLE (-1225 7800);
FORCEPROP 1 LAST COMMENT_BODY TRUE
J 0
(-1575 7825);
DISPLAY 1.170213 (-1575 7825);
PAINT GREEN (-1575 7825);
DISPLAY INVISIBLE (-1575 7825);
FORCEPROP 2 LAST PATH I48
J 0
(-1375 8000);
DISPLAY 1.021277 (-1375 8000);
DISPLAY INVISIBLE (-1375 8000);
FORCEADD OFFPAGE..4
(-1550 7975);
FORCEPROP 2 LAST $XR0 119 
J 0
(-1364 7975);
DISPLAY 0.638298 (-1364 7975);
PAINT MONO (-1364 7975);
FORCEPROP 2 LAST CDS_LIB standard
J 0
(-1550 7975);
PAINT MONO (-1550 7975);
DISPLAY INVISIBLE (-1550 7975);
FORCEPROP 1 LAST OFFPAGE TRUE
J 0
(-1225 7850);
DISPLAY 1.170213 (-1225 7850);
PAINT GREEN (-1225 7850);
DISPLAY INVISIBLE (-1225 7850);
FORCEPROP 1 LAST COMMENT_BODY TRUE
J 0
(-1575 7875);
DISPLAY 1.170213 (-1575 7875);
PAINT GREEN (-1575 7875);
DISPLAY INVISIBLE (-1575 7875);
FORCEPROP 2 LAST PATH I49
J 0
(-1375 8050);
DISPLAY 1.021277 (-1375 8050);
DISPLAY INVISIBLE (-1375 8050);
FORCEADD OFFPAGE..2
R 2
(-8450 6525);
FORCEPROP 2 LAST $XR1 132 
J 0
(-8794 6525);
DISPLAY 0.638298 (-8794 6525);
PAINT MONO (-8794 6525);
FORCEPROP 2 LAST $XR0 13 
J 0
(-8674 6525);
DISPLAY 0.638298 (-8674 6525);
PAINT MONO (-8674 6525);
FORCEPROP 2 LAST CDS_LIB standard
J 0
(-8450 6525);
PAINT MONO (-8450 6525);
DISPLAY INVISIBLE (-8450 6525);
FORCEPROP 1 LAST OFFPAGE TRUE
J 2
(-8775 6400);
DISPLAY 0.872340 (-8775 6400);
DISPLAY INVISIBLE (-8775 6400);
FORCEPROP 1 LAST COMMENT_BODY TRUE
J 2
(-8405 6430);
DISPLAY 0.872340 (-8405 6430);
PAINT GREEN (-8405 6430);
DISPLAY INVISIBLE (-8405 6430);
FORCEPROP 2 LAST PATH I5
J 0
(-8400 6600);
DISPLAY 1.021277 (-8400 6600);
DISPLAY INVISIBLE (-8400 6600);
FORCEADD OFFPAGE..4
(-1550 8025);
FORCEPROP 2 LAST $XR0 119 
J 0
(-1364 8025);
DISPLAY 0.638298 (-1364 8025);
PAINT MONO (-1364 8025);
FORCEPROP 2 LAST CDS_LIB standard
J 0
(-1550 8025);
PAINT MONO (-1550 8025);
DISPLAY INVISIBLE (-1550 8025);
FORCEPROP 1 LAST OFFPAGE TRUE
J 0
(-1225 7900);
DISPLAY 1.170213 (-1225 7900);
PAINT GREEN (-1225 7900);
DISPLAY INVISIBLE (-1225 7900);
FORCEPROP 1 LAST COMMENT_BODY TRUE
J 0
(-1575 7925);
DISPLAY 1.170213 (-1575 7925);
PAINT GREEN (-1575 7925);
DISPLAY INVISIBLE (-1575 7925);
FORCEPROP 2 LAST PATH I50
J 0
(-1375 8100);
DISPLAY 1.021277 (-1375 8100);
DISPLAY INVISIBLE (-1375 8100);
FORCEADD SOCKET4677_AZIF0045P001C01CS..1
(-4500 7100);
FORCEPROP 1 LAST PART_NUMBER DGA^7000023
J 0
(-5600 8300);
DISPLAY 0.723404 (-5600 8300);
PAINT GREEN (-5600 8300);
DISPLAY INVISIBLE (-5600 8300);
FORCEPROP 2 LAST VALUE SOCKET4677_AZIF0045-P001C01CS
J 0
(-5600 8425);
DISPLAY 1.021277 (-5600 8425);
FORCEPROP 2 LAST PART_TYPE SMLF
J 0
(-5600 8475);
DISPLAY 1.021277 (-5600 8475);
FORCEPROP 1 LAST MATERIAL IO
J 0
(-5600 8225);
DISPLAY 0.723404 (-5600 8225);
PAINT GREEN (-5600 8225);
FORCEPROP 1 LAST $LOCATION U1
J 0
(-5600 8375);
DISPLAY 0.723404 (-5600 8375);
PAINT GREEN (-5600 8375);
FORCEPROP 0 LASTPIN (-5725 7975) $PN AT30
J 2
(-5735 7985);
DISPLAY 0.680851 (-5735 7985);
PAINT MONO (-5735 7985);
FORCEPROP 0 LASTPIN (-5725 8025) $PN AV30
J 2
(-5735 8035);
DISPLAY 0.680851 (-5735 8035);
PAINT MONO (-5735 8035);
FORCEPROP 0 LASTPIN (-5725 7825) $PN CY28
J 2
(-5735 7835);
DISPLAY 0.680851 (-5735 7835);
PAINT MONO (-5735 7835);
FORCEPROP 0 LASTPIN (-5725 7875) $PN CW29
J 2
(-5735 7885);
DISPLAY 0.680851 (-5735 7885);
PAINT MONO (-5735 7885);
FORCEPROP 0 LASTPIN (-5725 7675) $PN AU29
J 2
(-5735 7685);
DISPLAY 0.680851 (-5735 7685);
PAINT MONO (-5735 7685);
FORCEPROP 0 LASTPIN (-5725 7725) $PN AV28
J 2
(-5735 7735);
DISPLAY 0.680851 (-5735 7735);
PAINT MONO (-5735 7735);
FORCEPROP 0 LASTPIN (-5725 7525) $PN CW27
J 2
(-5735 7535);
DISPLAY 0.680851 (-5735 7535);
PAINT MONO (-5735 7535);
FORCEPROP 0 LASTPIN (-5725 7575) $PN DA27
J 2
(-5735 7585);
DISPLAY 0.680851 (-5735 7585);
PAINT MONO (-5735 7585);
FORCEPROP 0 LASTPIN (-3275 8025) $PN AT18
J 0
(-3265 8035);
DISPLAY 0.680851 (-3265 8035);
PAINT MONO (-3265 8035);
FORCEPROP 0 LASTPIN (-3275 7975) $PN BN23
J 0
(-3265 7985);
DISPLAY 0.680851 (-3265 7985);
PAINT MONO (-3265 7985);
FORCEPROP 0 LASTPIN (-3275 6875) $PN AU50
J 0
(-3265 6885);
DISPLAY 0.680851 (-3265 6885);
PAINT MONO (-3265 6885);
FORCEPROP 0 LASTPIN (-3275 6825) $PN AV51
J 0
(-3265 6835);
DISPLAY 0.680851 (-3265 6835);
PAINT MONO (-3265 6835);
FORCEPROP 0 LASTPIN (-3275 6775) $PN CY42
J 0
(-3265 6785);
DISPLAY 0.680851 (-3265 6785);
PAINT MONO (-3265 6785);
FORCEPROP 0 LASTPIN (-3275 6725) $PN CY55
J 0
(-3265 6735);
DISPLAY 0.680851 (-3265 6735);
PAINT MONO (-3265 6735);
FORCEPROP 0 LASTPIN (-3275 7825) $PN AW17
J 0
(-3265 7835);
DISPLAY 0.680851 (-3265 7835);
PAINT MONO (-3265 7835);
FORCEPROP 0 LASTPIN (-3275 7725) $PN AU17
J 0
(-3265 7735);
DISPLAY 0.680851 (-3265 7735);
PAINT MONO (-3265 7735);
FORCEPROP 0 LASTPIN (-3275 7925) $PN CY59
J 0
(-3265 7935);
DISPLAY 0.680851 (-3265 7935);
PAINT MONO (-3265 7935);
FORCEPROP 0 LASTPIN (-5725 6375) $PN BH24
J 2
(-5735 6385);
DISPLAY 0.680851 (-5735 6385);
PAINT MONO (-5735 6385);
FORCEPROP 0 LASTPIN (-3275 7475) $PN BL64
J 0
(-3265 7485);
DISPLAY 0.680851 (-3265 7485);
PAINT MONO (-3265 7485);
FORCEPROP 0 LASTPIN (-3275 7425) $PN AY63
J 0
(-3265 7435);
DISPLAY 0.680851 (-3265 7435);
PAINT MONO (-3265 7435);
FORCEPROP 0 LASTPIN (-3275 7375) $PN BN64
J 0
(-3265 7385);
DISPLAY 0.680851 (-3265 7385);
PAINT MONO (-3265 7385);
FORCEPROP 0 LASTPIN (-5725 6525) $PN BP26
J 2
(-5735 6535);
DISPLAY 0.680851 (-5735 6535);
PAINT MONO (-5735 6535);
FORCEPROP 0 LASTPIN (-5725 6475) $PN AV22
J 2
(-5735 6485);
DISPLAY 0.680851 (-5735 6485);
PAINT MONO (-5735 6485);
FORCEPROP 0 LASTPIN (-3275 7325) $PN BG72
J 0
(-3265 7335);
DISPLAY 0.680851 (-3265 7335);
PAINT MONO (-3265 7335);
FORCEPROP 0 LASTPIN (-3275 7275) $PN BH71
J 0
(-3265 7285);
DISPLAY 0.680851 (-3265 7285);
PAINT MONO (-3265 7285);
FORCEPROP 0 LASTPIN (-3275 7175) $PN DA52
J 0
(-3265 7185);
DISPLAY 0.680851 (-3265 7185);
PAINT MONO (-3265 7185);
FORCEPROP 0 LASTPIN (-3275 7125) $PN AU23
J 0
(-3265 7135);
DISPLAY 0.680851 (-3265 7135);
PAINT MONO (-3265 7135);
FORCEPROP 0 LASTPIN (-3275 7625) $PN CW60
J 0
(-3265 7635);
DISPLAY 0.680851 (-3265 7635);
PAINT MONO (-3265 7635);
FORCEPROP 0 LASTPIN (-3275 7575) $PN CY61
J 0
(-3265 7585);
DISPLAY 0.680851 (-3265 7585);
PAINT MONO (-3265 7585);
FORCEPROP 0 LASTPIN (-3275 7525) $PN CT61
J 0
(-3265 7535);
DISPLAY 0.680851 (-3265 7535);
PAINT MONO (-3265 7535);
FORCEPROP 0 LASTPIN (-5725 6225) $PN BT24
J 2
(-5735 6235);
DISPLAY 0.680851 (-5735 6235);
PAINT MONO (-5735 6235);
FORCEPROP 0 LASTPIN (-5725 6275) $PN BV24
J 2
(-5735 6285);
DISPLAY 0.680851 (-5735 6285);
PAINT MONO (-5735 6285);
FORCEPROP 0 LASTPIN (-3275 6175) $PN BW25
J 0
(-3265 6185);
DISPLAY 0.680851 (-3265 6185);
PAINT MONO (-3265 6185);
FORCEPROP 0 LASTPIN (-5725 6175) $PN BR25
J 2
(-5735 6185);
DISPLAY 0.680851 (-5735 6185);
PAINT MONO (-5735 6185);
FORCEPROP 0 LASTPIN (-3275 7025) $PN BT26
J 0
(-3265 7035);
DISPLAY 0.680851 (-3265 7035);
PAINT MONO (-3265 7035);
FORCEPROP 0 LASTPIN (-3275 6975) $PN CT20
J 0
(-3265 6985);
DISPLAY 0.680851 (-3265 6985);
PAINT MONO (-3265 6985);
FORCEPROP 0 LASTPIN (-5725 7375) $PN CW31
J 2
(-5735 7385);
DISPLAY 0.680851 (-5735 7385);
PAINT MONO (-5735 7385);
FORCEPROP 0 LASTPIN (-5725 7425) $PN CY32
J 2
(-5735 7435);
DISPLAY 0.680851 (-5735 7435);
PAINT MONO (-5735 7435);
FORCEPROP 0 LASTPIN (-5725 6825) $PN BT22
J 2
(-5735 6835);
DISPLAY 0.680851 (-5735 6835);
PAINT MONO (-5735 6835);
FORCEPROP 0 LASTPIN (-5725 6775) $PN BY22
J 2
(-5735 6785);
DISPLAY 0.680851 (-5735 6785);
PAINT MONO (-5735 6785);
FORCEPROP 0 LASTPIN (-5725 6675) $PN CU17
J 2
(-5735 6685);
DISPLAY 0.680851 (-5735 6685);
PAINT MONO (-5735 6685);
FORCEPROP 0 LASTPIN (-5725 6625) $PN CT18
J 2
(-5735 6635);
DISPLAY 0.680851 (-5735 6635);
PAINT MONO (-5735 6635);
FORCEPROP 0 LASTPIN (-3275 6525) $PN BR23
J 0
(-3265 6535);
DISPLAY 0.680851 (-3265 6535);
PAINT MONO (-3265 6535);
FORCEPROP 0 LASTPIN (-3275 6625) $PN BY24
J 0
(-3265 6635);
DISPLAY 0.680851 (-3265 6635);
PAINT MONO (-3265 6635);
FORCEPROP 0 LASTPIN (-5725 6925) $PN CD71
J 2
(-5735 6935);
DISPLAY 0.680851 (-5735 6935);
PAINT MONO (-5735 6935);
FORCEPROP 0 LASTPIN (-5725 6975) $PN CE70
J 2
(-5735 6985);
DISPLAY 0.680851 (-5735 6985);
PAINT MONO (-5735 6985);
FORCEPROP 0 LASTPIN (-5725 7075) $PN CJ72
J 2
(-5735 7085);
DISPLAY 0.680851 (-5735 7085);
PAINT MONO (-5735 7085);
FORCEPROP 0 LASTPIN (-5725 7125) $PN CL72
J 2
(-5735 7135);
DISPLAY 0.680851 (-5735 7135);
PAINT MONO (-5735 7135);
FORCEPROP 0 LASTPIN (-5725 7225) $PN D4
J 2
(-5735 7235);
DISPLAY 0.680851 (-5735 7235);
PAINT MONO (-5735 7235);
FORCEPROP 0 LASTPIN (-5725 7275) $PN G5
J 2
(-5735 7285);
DISPLAY 0.680851 (-5735 7285);
PAINT MONO (-5735 7285);
FORCEPROP 1 LAST CDS_LMAN_SYM_OUTLINE -1100,1100,1050,-1050
J 0
(-4500 7100);
DISPLAY 0.468085 (-4500 7100);
PAINT GREEN (-4500 7100);
DISPLAY INVISIBLE (-4500 7100);
FORCEPROP 1 LAST NEEDS_NO_SIZE TRUE
J 0
(-4500 7100);
DISPLAY 0.723404 (-4500 7100);
PAINT GREEN (-4500 7100);
DISPLAY INVISIBLE (-4500 7100);
FORCEPROP 2 LAST CDS_LIB pure_quanta
J 0
(-4500 7100);
DISPLAY INVISIBLE (-4500 7100);
FORCEPROP 2 LAST CDS_LOCATION U1
J 0
(-5600 8525);
DISPLAY 1.021277 (-5600 8525);
DISPLAY INVISIBLE (-5600 8525);
FORCEPROP 0 LAST $SEC 1
J 0
(-5600 8525);
DISPLAY 0.680851 (-5600 8525);
PAINT MONO (-5600 8525);
DISPLAY INVISIBLE (-5600 8525);
FORCEPROP 2 LAST CDS_SEC 1
J 0
(-5600 8525);
DISPLAY 1.021277 (-5600 8525);
DISPLAY INVISIBLE (-5600 8525);
FORCEPROP 1 LAST PATH I51
J 0
(-4500 7100);
DISPLAY 0.723404 (-4500 7100);
PAINT GREEN (-4500 7100);
DISPLAY INVISIBLE (-4500 7100);
FORCEADD OFFPAGE..4
(-1550 6625);
FORCEPROP 2 LAST $XR0 119 
J 0
(-1364 6625);
DISPLAY 0.638298 (-1364 6625);
PAINT MONO (-1364 6625);
FORCEPROP 2 LAST CDS_LIB standard
J 0
(-1550 6625);
PAINT MONO (-1550 6625);
DISPLAY INVISIBLE (-1550 6625);
FORCEPROP 1 LAST OFFPAGE TRUE
J 0
(-1225 6500);
DISPLAY 1.170213 (-1225 6500);
PAINT GREEN (-1225 6500);
DISPLAY INVISIBLE (-1225 6500);
FORCEPROP 1 LAST COMMENT_BODY TRUE
J 0
(-1575 6525);
DISPLAY 1.170213 (-1575 6525);
PAINT GREEN (-1575 6525);
DISPLAY INVISIBLE (-1575 6525);
FORCEPROP 2 LAST PATH I52
J 0
(-1350 6675);
DISPLAY 1.021277 (-1350 6675);
DISPLAY INVISIBLE (-1350 6675);
FORCEADD OFFPAGE..4
(-1550 7175);
FORCEPROP 2 LAST $XR0 44 
J 0
(-1364 7175);
DISPLAY 0.638298 (-1364 7175);
PAINT MONO (-1364 7175);
FORCEPROP 2 LAST CDS_LIB standard
J 0
(-1550 7175);
PAINT MONO (-1550 7175);
DISPLAY INVISIBLE (-1550 7175);
FORCEPROP 1 LAST OFFPAGE TRUE
J 0
(-1225 7050);
DISPLAY 1.170213 (-1225 7050);
PAINT GREEN (-1225 7050);
DISPLAY INVISIBLE (-1225 7050);
FORCEPROP 1 LAST COMMENT_BODY TRUE
J 0
(-1575 7075);
DISPLAY 1.170213 (-1575 7075);
PAINT GREEN (-1575 7075);
DISPLAY INVISIBLE (-1575 7075);
FORCEPROP 2 LAST PATH I53
J 0
(-1350 7225);
DISPLAY 1.021277 (-1350 7225);
DISPLAY INVISIBLE (-1350 7225);
FORCEADD OFFPAGE..2
R 2
(-3300 5475);
FORCEPROP 2 LAST $XR0 44 
J 0
(-3554 5475);
DISPLAY 0.638298 (-3554 5475);
PAINT MONO (-3554 5475);
FORCEPROP 2 LAST CDS_LIB standard
J 0
(-3300 5475);
DISPLAY INVISIBLE (-3300 5475);
FORCEPROP 1 LAST OFFPAGE TRUE
J 2
(-3625 5350);
DISPLAY 0.872340 (-3625 5350);
DISPLAY INVISIBLE (-3625 5350);
FORCEPROP 1 LAST COMMENT_BODY TRUE
J 2
(-3255 5380);
DISPLAY 0.872340 (-3255 5380);
PAINT GREEN (-3255 5380);
DISPLAY INVISIBLE (-3255 5380);
FORCEPROP 2 LAST PATH I54
J 0
(-3600 5525);
DISPLAY 1.021277 (-3600 5525);
DISPLAY INVISIBLE (-3600 5525);
FORCEADD Q_RES..2
(-1575 5275);
FORCEPROP 1 LAST PART_NUMBER CS12402FB01
J 0
(-1535 5150);
DISPLAY 0.787234 (-1535 5150);
DISPLAY INVISIBLE (-1535 5150);
FORCEPROP 1 LAST PACK_TYPE 0402LF
J 0
(-1535 5100);
DISPLAY 0.787234 (-1535 5100);
FORCEPROP 1 LAST VALUE 240
J 0
(-1530 5350);
DISPLAY 0.787234 (-1530 5350);
FORCEPROP 1 LAST TOLERANCE 1%
J 0
(-1530 5300);
DISPLAY 0.787234 (-1530 5300);
FORCEPROP 1 LAST WATTAGE 1/16W
J 0
(-1535 5250);
DISPLAY 0.787234 (-1535 5250);
FORCEPROP 1 LAST MATERIAL EMPTY
J 0
(-1535 5200);
DISPLAY 0.787234 (-1535 5200);
PAINT RED (-1535 5200);
FORCEPROP 1 LAST $LOCATION R1270
J 0
(-1530 5400);
DISPLAY 0.978723 (-1530 5400);
FORCEPROP 1 LASTPIN (-1575 5375) $PN 1
J 0
(-1570 5337);
DISPLAY 0.787234 (-1570 5337);
FORCEPROP 1 LASTPIN (-1575 5175) $PN 2
J 0
(-1570 5185);
DISPLAY 0.787234 (-1570 5185);
FORCEPROP 2 LAST CDS_LIB pure_quanta
J 0
(-1575 5275);
PAINT MONO (-1575 5275);
DISPLAY INVISIBLE (-1575 5275);
FORCEPROP 2 LAST CDS_LOCATION R1270
J 0
(-1525 5500);
DISPLAY 1.021277 (-1525 5500);
DISPLAY INVISIBLE (-1525 5500);
FORCEPROP 2 LAST $SEC 1
J 0
(-1525 5500);
DISPLAY 0.680851 (-1525 5500);
PAINT MONO (-1525 5500);
DISPLAY INVISIBLE (-1525 5500);
FORCEPROP 2 LAST CDS_SEC 1
J 0
(-1525 5500);
DISPLAY 1.021277 (-1525 5500);
DISPLAY INVISIBLE (-1525 5500);
FORCEPROP 1 LAST PATH I55
J 0
(-1525 5450);
DISPLAY 0.978723 (-1525 5450);
PAINT WHITE (-1525 5450);
DISPLAY INVISIBLE (-1525 5450);
FORCEADD UNIVERSAL_GND..1
(-1575 5000);
FORCEPROP 3 LASTPIN (-1575 5050) SIG_NAME GND\g
J 0
(-1565 5060);
DISPLAY 0.659574 (-1565 5060);
PAINT MONO (-1565 5060);
DISPLAY INVISIBLE (-1565 5060);
FORCEPROP 2 LAST CDS_LIB logical_power
J 0
(-1575 5000);
PAINT MONO (-1575 5000);
DISPLAY INVISIBLE (-1575 5000);
FORCEPROP 1 LAST HDL_POWER GND
J 1
(-1550 4925);
DISPLAY 0.872340 (-1550 4925);
PAINT GREEN (-1550 4925);
DISPLAY INVISIBLE (-1550 4925);
FORCEPROP 1 LAST PATH I56
J 0
(-1500 5000);
DISPLAY 0.872340 (-1500 5000);
PAINT AQUA (-1500 5000);
DISPLAY INVISIBLE (-1500 5000);
FORCEADD OFFPAGE..1
(-7450 7125);
FORCEPROP 2 LAST $XR0 119 
J 0
(-7732 7125);
DISPLAY 0.638298 (-7732 7125);
PAINT MONO (-7732 7125);
FORCEPROP 2 LAST CDS_LIB standard
J 0
(-7450 7125);
PAINT MONO (-7450 7125);
DISPLAY INVISIBLE (-7450 7125);
FORCEPROP 1 LAST OFFPAGE TRUE
J 0
(-7125 7000);
DISPLAY 0.872340 (-7125 7000);
DISPLAY INVISIBLE (-7125 7000);
FORCEPROP 1 LAST COMMENT_BODY TRUE
J 0
(-7325 7025);
DISPLAY 0.872340 (-7325 7025);
PAINT GREEN (-7325 7025);
DISPLAY INVISIBLE (-7325 7025);
FORCEPROP 2 LAST PATH I57
J 0
(-7725 7175);
DISPLAY 1.021277 (-7725 7175);
DISPLAY INVISIBLE (-7725 7175);
FORCEADD OFFPAGE..1
(-7450 7075);
FORCEPROP 2 LAST $XR0 119 
J 0
(-7732 7075);
DISPLAY 0.638298 (-7732 7075);
PAINT MONO (-7732 7075);
FORCEPROP 2 LAST CDS_LIB standard
J 0
(-7450 7075);
PAINT MONO (-7450 7075);
DISPLAY INVISIBLE (-7450 7075);
FORCEPROP 1 LAST OFFPAGE TRUE
J 0
(-7125 6950);
DISPLAY 0.872340 (-7125 6950);
DISPLAY INVISIBLE (-7125 6950);
FORCEPROP 1 LAST COMMENT_BODY TRUE
J 0
(-7325 6975);
DISPLAY 0.872340 (-7325 6975);
PAINT GREEN (-7325 6975);
DISPLAY INVISIBLE (-7325 6975);
FORCEPROP 2 LAST PATH I58
J 0
(-7725 7125);
DISPLAY 1.021277 (-7725 7125);
DISPLAY INVISIBLE (-7725 7125);
FORCEADD OFFPAGE..1
(-8450 6475);
FORCEPROP 2 LAST $XR1 13 
J 0
(-8822 6475);
DISPLAY 0.638298 (-8822 6475);
PAINT MONO (-8822 6475);
FORCEPROP 2 LAST $XR0 132 
J 0
(-8732 6475);
DISPLAY 0.638298 (-8732 6475);
PAINT MONO (-8732 6475);
FORCEPROP 2 LAST CDS_LIB standard
J 0
(-8450 6475);
PAINT MONO (-8450 6475);
DISPLAY INVISIBLE (-8450 6475);
FORCEPROP 1 LAST OFFPAGE TRUE
J 0
(-8125 6350);
DISPLAY 0.872340 (-8125 6350);
DISPLAY INVISIBLE (-8125 6350);
FORCEPROP 1 LAST COMMENT_BODY TRUE
J 0
(-8325 6375);
DISPLAY 0.872340 (-8325 6375);
PAINT GREEN (-8325 6375);
DISPLAY INVISIBLE (-8325 6375);
FORCEPROP 2 LAST PATH I6
J 0
(-8400 6550);
DISPLAY 1.021277 (-8400 6550);
DISPLAY INVISIBLE (-8400 6550);
FORCEADD Q_RES..1
(-7325 6175);
FORCEPROP 1 LAST PART_NUMBER CS11002FB07
J 0
(-7200 6150);
DISPLAY 0.404255 (-7200 6150);
DISPLAY INVISIBLE (-7200 6150);
FORCEPROP 1 LAST VALUE 100
J 2
(-7125 6175);
DISPLAY 0.510638 (-7125 6175);
FORCEPROP 1 LAST TOLERANCE 1%
J 0
(-7100 6175);
DISPLAY 0.510638 (-7100 6175);
FORCEPROP 1 LAST MATERIAL CHIP
J 0
(-7200 6125);
DISPLAY 0.404255 (-7200 6125);
FORCEPROP 1 LAST WATTAGE 1/16W
J 2
(-6900 6125);
DISPLAY 0.404255 (-6900 6125);
FORCEPROP 1 LAST PACK_TYPE 0402LF
J 0
(-7000 6175);
DISPLAY 0.510638 (-7000 6175);
FORCEPROP 1 LAST $LOCATION R66
J 0
(-7525 6175);
DISPLAY 0.638298 (-7525 6175);
FORCEPROP 1 LASTPIN (-7425 6175) $PN 1
J 0
(-7413 6187);
DISPLAY 0.787234 (-7413 6187);
FORCEPROP 1 LASTPIN (-7225 6175) $PN 2
J 0
(-7263 6187);
DISPLAY 0.787234 (-7263 6187);
FORCEPROP 2 LAST CDS_LIB pure_quanta
J 0
(-7325 6175);
PAINT MONO (-7325 6175);
DISPLAY INVISIBLE (-7325 6175);
FORCEPROP 1 LAST $LOCATION R66
J 0
(-7375 6375);
DISPLAY 1.021277 (-7375 6375);
DISPLAY INVISIBLE (-7375 6375);
FORCEPROP 2 LAST CDS_LOCATION R66
J 0
(-7375 6375);
DISPLAY 1.021277 (-7375 6375);
DISPLAY INVISIBLE (-7375 6375);
FORCEPROP 2 LAST $SEC 1
J 0
(-7375 6375);
DISPLAY 0.680851 (-7375 6375);
PAINT MONO (-7375 6375);
DISPLAY INVISIBLE (-7375 6375);
FORCEPROP 2 LAST CDS_SEC 1
J 0
(-7375 6375);
DISPLAY 1.021277 (-7375 6375);
DISPLAY INVISIBLE (-7375 6375);
FORCEPROP 1 LAST PATH I7
J 0
(-7375 6325);
DISPLAY 0.978723 (-7375 6325);
PAINT WHITE (-7375 6325);
DISPLAY INVISIBLE (-7375 6325);
FORCEADD Q_RES..1
(-7325 6225);
FORCEPROP 1 LAST PART_NUMBER CS11002FB07
J 0
(-7400 6175);
DISPLAY 0.404255 (-7400 6175);
DISPLAY INVISIBLE (-7400 6175);
FORCEPROP 1 LAST VALUE 100
J 2
(-7125 6225);
DISPLAY 0.510638 (-7125 6225);
FORCEPROP 1 LAST TOLERANCE 1%
J 0
(-7100 6225);
DISPLAY 0.510638 (-7100 6225);
FORCEPROP 1 LAST PACK_TYPE 0402LF
J 0
(-7000 6225);
DISPLAY 0.510638 (-7000 6225);
FORCEPROP 1 LAST $LOCATION R65
J 0
(-7525 6225);
DISPLAY 0.638298 (-7525 6225);
FORCEPROP 1 LASTPIN (-7425 6225) $PN 1
J 0
(-7413 6237);
DISPLAY 0.787234 (-7413 6237);
FORCEPROP 1 LASTPIN (-7225 6225) $PN 2
J 0
(-7263 6237);
DISPLAY 0.787234 (-7263 6237);
FORCEPROP 2 LAST CDS_LIB pure_quanta
J 0
(-7325 6225);
PAINT MONO (-7325 6225);
DISPLAY INVISIBLE (-7325 6225);
FORCEPROP 1 LAST MATERIAL CHIP
J 0
(-7175 6175);
DISPLAY 0.404255 (-7175 6175);
DISPLAY INVISIBLE (-7175 6175);
FORCEPROP 1 LAST WATTAGE 1/16W
J 2
(-6975 6175);
DISPLAY 0.404255 (-6975 6175);
DISPLAY INVISIBLE (-6975 6175);
FORCEPROP 1 LAST $LOCATION R65
J 0
(-7375 6425);
DISPLAY 1.021277 (-7375 6425);
DISPLAY INVISIBLE (-7375 6425);
FORCEPROP 2 LAST CDS_LOCATION R65
J 0
(-7375 6425);
DISPLAY 1.021277 (-7375 6425);
DISPLAY INVISIBLE (-7375 6425);
FORCEPROP 2 LAST $SEC 1
J 0
(-7375 6425);
DISPLAY 0.680851 (-7375 6425);
PAINT MONO (-7375 6425);
DISPLAY INVISIBLE (-7375 6425);
FORCEPROP 2 LAST CDS_SEC 1
J 0
(-7375 6425);
DISPLAY 1.021277 (-7375 6425);
DISPLAY INVISIBLE (-7375 6425);
FORCEPROP 1 LAST PATH I8
J 0
(-7375 6375);
DISPLAY 0.978723 (-7375 6375);
PAINT WHITE (-7375 6375);
DISPLAY INVISIBLE (-7375 6375);
FORCEADD Q_RES..1
(-7325 6275);
FORCEPROP 1 LAST PART_NUMBER CS12002FB06
J 0
(-7200 6300);
DISPLAY 0.404255 (-7200 6300);
DISPLAY INVISIBLE (-7200 6300);
FORCEPROP 1 LAST WATTAGE 1/16W
J 2
(-6875 6300);
DISPLAY 0.404255 (-6875 6300);
FORCEPROP 1 LAST PACK_TYPE 0402LF
J 0
(-7000 6275);
DISPLAY 0.510638 (-7000 6275);
FORCEPROP 1 LAST VALUE 200
J 2
(-7125 6275);
DISPLAY 0.510638 (-7125 6275);
FORCEPROP 1 LAST TOLERANCE 1%
J 0
(-7100 6275);
DISPLAY 0.510638 (-7100 6275);
FORCEPROP 1 LAST MATERIAL CHIP
J 0
(-6850 6300);
DISPLAY 0.404255 (-6850 6300);
FORCEPROP 1 LAST $LOCATION R64
J 0
(-7525 6275);
DISPLAY 0.638298 (-7525 6275);
FORCEPROP 1 LASTPIN (-7425 6275) $PN 1
J 0
(-7413 6287);
DISPLAY 0.787234 (-7413 6287);
FORCEPROP 1 LASTPIN (-7225 6275) $PN 2
J 0
(-7263 6287);
DISPLAY 0.787234 (-7263 6287);
FORCEPROP 2 LAST CDS_LIB pure_quanta
J 0
(-7325 6275);
PAINT MONO (-7325 6275);
DISPLAY INVISIBLE (-7325 6275);
FORCEPROP 1 LAST $LOCATION R64
J 0
(-7375 6475);
DISPLAY 1.021277 (-7375 6475);
DISPLAY INVISIBLE (-7375 6475);
FORCEPROP 2 LAST CDS_LOCATION R64
J 0
(-7375 6475);
DISPLAY 1.021277 (-7375 6475);
DISPLAY INVISIBLE (-7375 6475);
FORCEPROP 2 LAST $SEC 1
J 0
(-7375 6475);
DISPLAY 0.680851 (-7375 6475);
PAINT MONO (-7375 6475);
DISPLAY INVISIBLE (-7375 6475);
FORCEPROP 2 LAST CDS_SEC 1
J 0
(-7375 6475);
DISPLAY 1.021277 (-7375 6475);
DISPLAY INVISIBLE (-7375 6475);
FORCEPROP 1 LAST PATH I9
J 0
(-7375 6425);
DISPLAY 0.978723 (-7375 6425);
PAINT WHITE (-7375 6425);
DISPLAY INVISIBLE (-7375 6425);
FORCEADD DNS..2
(-1570 5270);
PAINT RED (-1570 5270);
FORCEPROP 2 LAST CDS_LIB mstr_misc
J 0
(-1570 5270);
PAINT MONO (-1570 5270);
DISPLAY INVISIBLE (-1570 5270);
FORCEPROP 1 LAST COMMENT_BODY TRUE
J 0
(-1570 5270);
DISPLAY INVISIBLE (-1570 5270);
FORCEADD QUANTA_TITLE_BLOCK_C..1
(25 2725);
FORCEPROP 0 LAST CDS_CON_LAST_MODIFIED Fri Aug 25 14:00:27 2023
J 0
(-1860 2740);
PAINT MONO (-1860 2740);
DISPLAY INVISIBLE (-1860 2740);
FORCEPROP 2 LAST CUSTOM_TXT_CDS <XR_PAGE_TITLE>
J 0
(-7865 7975);
DISPLAY 0.638298 (-7865 7975);
PAINT PINK (-7865 7975);
DISPLAY INVISIBLE (-7865 7975);
FORCEPROP 2 LAST CUSTOM_TXT_CDS <NAME_1>
J 0
(-3150 2900);
FORCEPROP 2 LAST CUSTOM_TXT_CDS <NAME_2>
J 0
(-3150 2775);
FORCEPROP 2 LAST CUSTOM_TXT_CDS <Q_NUMBER>
J 0
(-1378 2828);
DISPLAY 1.212766 (-1378 2828);
FORCEPROP 2 LAST CUSTOM_TXT_CDS <Q_PROJ>
J 0
(-2357 2827);
DISPLAY 1.212766 (-2357 2827);
FORCEPROP 2 LAST CUSTOM_TXT_CDS <Q_REV>
J 0
(-159 2828);
DISPLAY 1.212766 (-159 2828);
FORCEPROP 2 LAST CUSTOM_TXT_CDS <CON_PAGE_NUM> OF <CON_TOTAL_PAGES>
J 0
(-421 2743);
DISPLAY 0.978723 (-421 2743);
FORCEPROP 2 LAST CUSTOM_TXT_CDS <CON_LAST_MODIFIED>
J 0
(-1860 2740);
DISPLAY 0.978723 (-1860 2740);
FORCEPROP 1 LAST Q_TITLE SPR CPU1 MISC:CLK/JTAG/STRAPS(1/30)
J 0
(-9341 2751);
DISPLAY 1.957447 (-9341 2751);
PAINT GREEN (-9341 2751);
FORCEPROP 1 LAST Q_DEPT 
J 1
(-3738 2774);
DISPLAY 1.957447 (-3738 2774);
PAINT GREEN (-3738 2774);
FORCEPROP 2 LAST PAGE_BORDER TRUE
J 0
(-7865 7975);
DISPLAY 0.638298 (-7865 7975);
PAINT PINK (-7865 7975);
DISPLAY INVISIBLE (-7865 7975);
FORCEPROP 1 LAST CDS_LMAN_SYM_OUTLINE -9475,6775,100,-125
J 0
(25 2725);
DISPLAY 0.468085 (25 2725);
PAINT GREEN (25 2725);
DISPLAY INVISIBLE (25 2725);
FORCEPROP 2 LAST CDS_LIB pure_quanta
J 0
(25 2725);
PAINT MONO (25 2725);
DISPLAY INVISIBLE (25 2725);
FORCEPROP 2 LAST CDS_XR_PAGE_TITLE CR-44 : @S9S_MB_2U_LIB.S9S_MB_2U(SCH_1):PAGE44
J 0
(-7865 7975);
DISPLAY 0.638298 (-7865 7975);
PAINT PINK (-7865 7975);
DISPLAY INVISIBLE (-7865 7975);
FORCEPROP 1 LAST COMMENT_BODY TRUE
J 0
(37 2712);
DISPLAY 0.978723 (37 2712);
PAINT GREEN (37 2712);
DISPLAY INVISIBLE (37 2712);
WIRE 16 -1 (-1575 5050)(-1575 5175);
WIRE 16 -1 (-5725 7425)(-7400 7425);
FORCEPROP 2 LAST SIG_NAME CLK_25M_NSSC_CPU1_DP
J 0
(-7337 7434);
DISPLAY 0.680851 (-7337 7434);
PAINT WHITE (-7337 7434);
WIRE 16 -1 (-1600 6975)(-3275 6975);
FORCEPROP 2 LAST SIG_NAME PD_CPU1_TXT_PLTEN
J 0
(-3016 6984);
DISPLAY 0.680851 (-3016 6984);
PAINT WHITE (-3016 6984);
WIRE 16 -1 (-1600 7025)(-3275 7025);
FORCEPROP 2 LAST SIG_NAME PU_CPU1_TXT_AGENT
J 0
(-3016 7034);
DISPLAY 0.680851 (-3016 7034);
PAINT WHITE (-3016 7034);
WIRE 16 -1 (-5725 6175)(-7225 6175);
FORCEPROP 2 LAST SIG_NAME JTAG_DBP_CPU1_QS_GTL_R_TMS
J 0
(-6762 6184);
DISPLAY 0.680851 (-6762 6184);
PAINT WHITE (-6762 6184);
WIRE 16 -1 (-1600 6175)(-3275 6175);
FORCEPROP 2 LAST SIG_NAME JTAG_CPU1_MUX_GTL_TDO
J 0
(-3016 6184);
DISPLAY 0.680851 (-3016 6184);
PAINT WHITE (-3016 6184);
WIRE 16 -1 (-5725 6275)(-7225 6275);
FORCEPROP 2 LAST SIG_NAME JTAG_DBP_CPU1_GTL_R_TDI
J 0
(-6762 6284);
DISPLAY 0.680851 (-6762 6284);
PAINT WHITE (-6762 6284);
WIRE 16 -1 (-5725 6225)(-7225 6225);
FORCEPROP 2 LAST SIG_NAME JTAG_DBP_CPU1_GTL_R_TCK
J 0
(-6762 6234);
DISPLAY 0.680851 (-6762 6234);
PAINT WHITE (-6762 6234);
WIRE 16 -1 (-1600 7625)(-3275 7625);
FORCEPROP 2 LAST SIG_NAME PU_CPU1_SOCKET_ID0
J 0
(-3016 7634);
DISPLAY 0.680851 (-3016 7634);
PAINT WHITE (-3016 7634);
WIRE 16 -1 (-1600 7575)(-3275 7575);
FORCEPROP 2 LAST SIG_NAME PU_CPU1_SOCKET_ID1
J 0
(-3016 7584);
DISPLAY 0.680851 (-3016 7584);
PAINT WHITE (-3016 7584);
WIRE 16 -1 (-1600 7525)(-3275 7525);
FORCEPROP 2 LAST SIG_NAME PU_CPU1_SOCKET_ID2
J 0
(-3016 7534);
DISPLAY 0.680851 (-3016 7534);
PAINT WHITE (-3016 7534);
WIRE 16 -1 (-1600 7125)(-3275 7125);
FORCEPROP 2 LAST SIG_NAME PU_CPU1_SAFE_MODE_BOOT
J 0
(-3016 7134);
DISPLAY 0.680851 (-3016 7134);
PAINT WHITE (-3016 7134);
WIRE 16 -1 (-5725 6975)(-7400 6975);
FORCEPROP 2 LAST SIG_NAME CPU1_RSVD<85>
J 0
(-7337 6984);
DISPLAY 0.680851 (-7337 6984);
PAINT WHITE (-7337 6984);
WIRE 16 -1 (-5725 6925)(-7400 6925);
FORCEPROP 2 LAST SIG_NAME CPU1_RSVD<82>
J 0
(-7337 6934);
DISPLAY 0.680851 (-7337 6934);
PAINT WHITE (-7337 6934);
WIRE 16 -1 (-1600 6625)(-3275 6625);
FORCEPROP 2 LAST SIG_NAME PD_EXT_CLK_SEL_CPU1
J 0
(-3016 6634);
DISPLAY 0.680851 (-3016 6634);
PAINT WHITE (-3016 6634);
WIRE 16 -1 (-5725 7275)(-7400 7275);
FORCEPROP 2 LAST SIG_NAME CPU1_RSVD<157>
J 0
(-7337 7284);
DISPLAY 0.680851 (-7337 7284);
PAINT WHITE (-7337 7284);
WIRE 16 -1 (-5725 7075)(-7400 7075);
FORCEPROP 2 LAST SIG_NAME PUD_XTAL_CPU1_MODE1
J 0
(-7337 7084);
DISPLAY 0.680851 (-7337 7084);
PAINT WHITE (-7337 7084);
WIRE 16 -1 (-1600 7325)(-3275 7325);
FORCEPROP 2 LAST SIG_NAME FM_CPU1_PROC_ID0
J 0
(-3016 7334);
DISPLAY 0.680851 (-3016 7334);
PAINT WHITE (-3016 7334);
WIRE 16 -1 (-1600 7275)(-3275 7275);
FORCEPROP 2 LAST SIG_NAME FM_CPU1_PROC_ID1
J 0
(-3016 7284);
DISPLAY 0.680851 (-3016 7284);
PAINT WHITE (-3016 7284);
WIRE 16 -1 (-1600 7175)(-3275 7175);
FORCEPROP 2 LAST SIG_NAME PD_CPU1_PROCDIS_COD_GTL_N
J 0
(-3016 7184);
DISPLAY 0.680851 (-3016 7184);
PAINT WHITE (-3016 7184);
WIRE 16 -1 (-5725 6475)(-7225 6475);
FORCEPROP 2 LAST SIG_NAME H_CPU1_PREQ_QS_GTL_R_N
J 0
(-6762 6484);
DISPLAY 0.680851 (-6762 6484);
PAINT WHITE (-6762 6484);
WIRE 16 -1 (-5725 6525)(-7225 6525);
FORCEPROP 2 LAST SIG_NAME H_CPU1_PRDY_QS_GTL_R_N
J 0
(-6762 6534);
DISPLAY 0.680851 (-6762 6534);
PAINT WHITE (-6762 6534);
WIRE 16 -1 (-1600 7475)(-3275 7475);
FORCEPROP 2 LAST SIG_NAME FM_CPU1_PKGID0
J 0
(-3016 7484);
DISPLAY 0.680851 (-3016 7484);
PAINT WHITE (-3016 7484);
WIRE 16 -1 (-1600 7425)(-3275 7425);
FORCEPROP 2 LAST SIG_NAME FM_CPU1_PKGID1
J 0
(-3016 7434);
DISPLAY 0.680851 (-3016 7434);
PAINT WHITE (-3016 7434);
WIRE 16 -1 (-1600 7375)(-3275 7375);
FORCEPROP 2 LAST SIG_NAME FM_CPU1_PKGID2
J 0
(-3016 7384);
DISPLAY 0.680851 (-3016 7384);
PAINT WHITE (-3016 7384);
WIRE 16 -1 (-5725 6375)(-7225 6375);
FORCEPROP 2 LAST SIG_NAME PECI_CPU1_GTL_R
J 0
(-6762 6384);
DISPLAY 0.680851 (-6762 6384);
PAINT WHITE (-6762 6384);
WIRE 16 -1 (-1600 6525)(-3275 6525);
FORCEPROP 2 LAST SIG_NAME TP_CPU1_BR23
J 0
(-3016 6534);
DISPLAY 0.680851 (-3016 6534);
PAINT WHITE (-3016 6534);
WIRE 16 -1 (-1600 7925)(-3275 7925);
FORCEPROP 2 LAST SIG_NAME PU_CPU1_LEGACY_SKT
J 0
(-3016 7934);
DISPLAY 0.680851 (-3016 7934);
PAINT WHITE (-3016 7934);
WIRE 16 -1 (-1600 7725)(-3275 7725);
FORCEPROP 2 LAST SIG_NAME PU_CPU1_FRMAGENT
J 0
(-3016 7734);
DISPLAY 0.680851 (-3016 7734);
PAINT WHITE (-3016 7734);
WIRE 16 -1 (-1600 7825)(-3275 7825);
FORCEPROP 2 LAST SIG_NAME PD_CPU1_DMIMODE_OVERRIDE
J 0
(-3016 7834);
DISPLAY 0.680851 (-3016 7834);
PAINT WHITE (-3016 7834);
WIRE 16 -1 (-1600 6725)(-3275 6725);
FORCEPROP 2 LAST SIG_NAME RST_CPU1_DRAM_GH_N
J 0
(-3016 6734);
DISPLAY 0.680851 (-3016 6734);
PAINT WHITE (-3016 6734);
WIRE 16 -1 (-1600 6775)(-3275 6775);
FORCEPROP 2 LAST SIG_NAME RST_CPU1_DRAM_EF_N
J 0
(-3016 6784);
DISPLAY 0.680851 (-3016 6784);
PAINT WHITE (-3016 6784);
WIRE 16 -1 (-5725 6625)(-7400 6625);
FORCEPROP 2 LAST SIG_NAME I3C_SPD_DDREFGH_CPU1_SDA
J 0
(-7337 6634);
DISPLAY 0.680851 (-7337 6634);
PAINT WHITE (-7337 6634);
WIRE 16 -1 (-5725 6675)(-7400 6675);
FORCEPROP 2 LAST SIG_NAME I3C_SPD_DDREFGH_CPU1_SCL
J 0
(-7337 6684);
DISPLAY 0.680851 (-7337 6684);
PAINT WHITE (-7337 6684);
WIRE 16 -1 (-1600 6825)(-3275 6825);
FORCEPROP 2 LAST SIG_NAME RST_CPU1_DRAM_CD_N
J 0
(-3016 6834);
DISPLAY 0.680851 (-3016 6834);
PAINT WHITE (-3016 6834);
WIRE 16 -1 (-1600 6875)(-3275 6875);
FORCEPROP 2 LAST SIG_NAME RST_CPU1_DRAM_AB_N
J 0
(-3016 6884);
DISPLAY 0.680851 (-3016 6884);
PAINT WHITE (-3016 6884);
WIRE 16 -1 (-5725 6775)(-7400 6775);
FORCEPROP 2 LAST SIG_NAME I3C_SPD_DDRABCD_CPU1_SDA
J 0
(-7337 6784);
DISPLAY 0.680851 (-7337 6784);
PAINT WHITE (-7337 6784);
WIRE 16 -1 (-5725 6825)(-7400 6825);
FORCEPROP 2 LAST SIG_NAME I3C_SPD_DDRABCD_CPU1_SCL
J 0
(-7337 6834);
DISPLAY 0.680851 (-7337 6834);
PAINT WHITE (-7337 6834);
WIRE 16 -1 (-1600 7975)(-3275 7975);
FORCEPROP 2 LAST SIG_NAME H_CPU1_BMCINIT_LVC1
J 0
(-3016 7984);
DISPLAY 0.680851 (-3016 7984);
PAINT WHITE (-3016 7984);
WIRE 16 -1 (-1600 8025)(-3275 8025);
FORCEPROP 2 LAST SIG_NAME PD_CPU1_BIST_ENABLE
J 0
(-3016 8033);
DISPLAY 0.680851 (-3016 8033);
PAINT WHITE (-3016 8033);
WIRE 16 -1 (-5725 7575)(-7400 7575);
FORCEPROP 2 LAST SIG_NAME CLK_100M_DB2000_CPU1_BCLK3_DP
J 0
(-7337 7584);
DISPLAY 0.680851 (-7337 7584);
PAINT WHITE (-7337 7584);
WIRE 16 -1 (-5725 7525)(-7400 7525);
FORCEPROP 2 LAST SIG_NAME CLK_100M_DB2000_CPU1_BCLK3_DN
J 0
(-7335 7533);
DISPLAY 0.680851 (-7335 7533);
PAINT WHITE (-7335 7533);
WIRE 16 -1 (-5725 7725)(-7400 7725);
FORCEPROP 2 LAST SIG_NAME CLK_100M_DB2000_CPU1_BCLK2_DP
J 0
(-7337 7734);
DISPLAY 0.680851 (-7337 7734);
PAINT WHITE (-7337 7734);
WIRE 16 -1 (-5725 7675)(-7400 7675);
FORCEPROP 2 LAST SIG_NAME CLK_100M_DB2000_CPU1_BCLK2_DN
J 0
(-7335 7683);
DISPLAY 0.680851 (-7335 7683);
PAINT WHITE (-7335 7683);
WIRE 16 -1 (-5725 8025)(-7400 8025);
FORCEPROP 2 LAST SIG_NAME CLK_100M_DB2000_CPU1_BCLK0_DP
J 0
(-7341 8033);
DISPLAY 0.680851 (-7341 8033);
PAINT WHITE (-7341 8033);
WIRE 16 -1 (-5725 7825)(-7400 7825);
FORCEPROP 2 LAST SIG_NAME CLK_100M_DB2000_CPU1_BCLK1_DN
J 0
(-7340 7832);
DISPLAY 0.680851 (-7340 7832);
PAINT WHITE (-7340 7832);
WIRE 16 -1 (-5725 7875)(-7400 7875);
FORCEPROP 2 LAST SIG_NAME CLK_100M_DB2000_CPU1_BCLK1_DP
J 0
(-7339 7882);
DISPLAY 0.680851 (-7339 7882);
PAINT WHITE (-7339 7882);
WIRE 16 -1 (-5725 7975)(-7400 7975);
FORCEPROP 2 LAST SIG_NAME CLK_100M_DB2000_CPU1_BCLK0_DN
J 0
(-7341 7984);
DISPLAY 0.680851 (-7341 7984);
PAINT WHITE (-7341 7984);
WIRE 16 -1 (-5725 7125)(-7400 7125);
FORCEPROP 2 LAST SIG_NAME PUD_XTAL_CPU1_MODE0
J 0
(-7337 7134);
DISPLAY 0.680851 (-7337 7134);
PAINT WHITE (-7337 7134);
WIRE 16 -1 (-5725 7225)(-7400 7225);
FORCEPROP 2 LAST SIG_NAME CPU1_RSVD<153>
J 0
(-7337 7234);
DISPLAY 0.680851 (-7337 7234);
PAINT WHITE (-7337 7234);
WIRE 16 -1 (-5725 7375)(-7400 7375);
FORCEPROP 2 LAST SIG_NAME CLK_25M_NSSC_CPU1_DN
J 0
(-7337 7384);
DISPLAY 0.680851 (-7337 7384);
PAINT WHITE (-7337 7384);
WIRE 16 -1 (-3250 5475)(-1575 5475);
FORCEPROP 2 LAST SIG_NAME PD_CPU1_PROCDIS_COD_GTL_N
J 0
(-2991 5484);
DISPLAY 0.680851 (-2991 5484);
PAINT WHITE (-2991 5484);
WIRE 16 -1 (-1575 5375)(-1575 5475);
WIRE 16 -1 (-7425 6375)(-8400 6375);
FORCEPROP 2 LAST SIG_NAME PECI_CPU_GTL
J 0
(-8337 6384);
DISPLAY 0.680851 (-8337 6384);
PAINT WHITE (-8337 6384);
WIRE 16 -1 (-7425 6275)(-8400 6275);
FORCEPROP 2 LAST SIG_NAME JTAG_MUX_CPU1_GTL_TDI
J 0
(-8337 6284);
DISPLAY 0.680851 (-8337 6284);
PAINT WHITE (-8337 6284);
WIRE 16 -1 (-7425 6525)(-8400 6525);
FORCEPROP 2 LAST SIG_NAME H_CPU_PRDY_QS_GTL_N
J 0
(-8337 6534);
DISPLAY 0.680851 (-8337 6534);
PAINT WHITE (-8337 6534);
WIRE 16 -1 (-7425 6475)(-8400 6475);
FORCEPROP 2 LAST SIG_NAME H_CPU_PREQ_QS_GTL_N
J 0
(-8337 6484);
DISPLAY 0.680851 (-8337 6484);
PAINT WHITE (-8337 6484);
WIRE 16 -1 (-7425 6225)(-8400 6225);
FORCEPROP 2 LAST SIG_NAME JTAG_DBP_CPU_GTL_TCK
J 0
(-8337 6234);
DISPLAY 0.680851 (-8337 6234);
PAINT WHITE (-8337 6234);
WIRE 16 -1 (-7425 6175)(-8400 6175);
FORCEPROP 2 LAST SIG_NAME JTAG_DBP_CPU_QS_GTL_TMS
J 0
(-8337 6184);
DISPLAY 0.680851 (-8337 6184);
PAINT WHITE (-8337 6184);
QUIT
